(kicad_sch
	(version 20250114)
	(generator "eeschema")
	(generator_version "9.0")
	(paper "A3")
	(title_block
		(title "DDR5 testbed")
		(date "2024-05-27")
		(rev "1.1.2")
		(comment 1 "www.antmicro.com")
		(comment 2 "Antmicro Ltd.")
	)
	(text "DDR5 testbed"
		(exclude_from_sim no)
		(at 18.415 21.59 0)
		(effects
			(font
				(size 2.4892 2.4892)
				(thickness 0.4978)
				(bold yes)
			)
			(justify left bottom)
		)
	)
	(symbol
		(lib_id "antmicroMechanicalParts:oshw_logo")
		(at 387.985 248.285 0)
		(unit 1)
		(exclude_from_sim no)
		(in_bom yes)
		(on_board yes)
		(dnp no)
		(fields_autoplaced yes)
		(property "Reference" "N2"
			(at 393.7 245.9925 0)
			(effects
				(font
					(size 1.27 1.27)
				)
				(justify left)
			)
		)
		(property "Value" "oshw_logo"
			(at 393.7 248.5325 0)
			(effects
				(font
					(size 1.27 1.27)
					(thickness 0.15)
				)
				(justify left)
			)
		)
		(property "Footprint" "antmicro-footprints:oshw-logo"
			(at 403.225 258.445 0)
			(effects
				(font
					(size 1.27 1.27)
					(thickness 0.15)
				)
				(justify left bottom)
				(hide yes)
			)
		)
		(property "Datasheet" ""
			(at 403.225 260.985 0)
			(effects
				(font
					(size 1.27 1.27)
					(thickness 0.15)
				)
				(justify left bottom)
				(hide yes)
			)
		)
		(property "Description" ""
			(at 387.985 248.285 0)
			(effects
				(font
					(size 1.27 1.27)
				)
			)
		)
		(property "Author" "Antmicro"
			(at 403.225 263.525 0)
			(effects
				(font
					(size 1.27 1.27)
					(thickness 0.15)
				)
				(justify left bottom)
				(hide yes)
			)
		)
		(property "License" "Apache-2.0"
			(at 403.225 266.065 0)
			(effects
				(font
					(size 1.27 1.27)
					(thickness 0.15)
				)
				(justify left bottom)
				(hide yes)
			)
		)
		(property "MPN" ""
			(at 387.985 248.285 0)
			(effects
				(font
					(size 1.27 1.27)
				)
				(hide yes)
			)
		)
		(property "Manufacturer" ""
			(at 403.225 268.605 0)
			(effects
				(font
					(size 1.27 1.27)
					(thickness 0.15)
				)
				(justify left bottom)
				(hide yes)
			)
		)
		(instances
			(project "ddr5-testbed"
				(path ""
					(reference "N2")
					(unit 1)
				)
			)
		)
	)
	(symbol
		(lib_id "antmicroMechanicalParts:antmicro_logo")
		(at 387.985 243.205 0)
		(unit 1)
		(exclude_from_sim no)
		(in_bom yes)
		(on_board yes)
		(dnp no)
		(fields_autoplaced yes)
		(property "Reference" "N1"
			(at 393.7 240.9125 0)
			(effects
				(font
					(size 1.27 1.27)
				)
				(justify left)
			)
		)
		(property "Value" "antmicro_logo"
			(at 393.7 243.4525 0)
			(effects
				(font
					(size 1.27 1.27)
					(thickness 0.15)
				)
				(justify left)
			)
		)
		(property "Footprint" "antmicro-footprints:antmicro-logo_scaled_20mm"
			(at 403.225 253.365 0)
			(effects
				(font
					(size 1.27 1.27)
					(thickness 0.15)
				)
				(justify left bottom)
				(hide yes)
			)
		)
		(property "Datasheet" ""
			(at 403.225 255.905 0)
			(effects
				(font
					(size 1.27 1.27)
					(thickness 0.15)
				)
				(justify left bottom)
				(hide yes)
			)
		)
		(property "Description" ""
			(at 387.985 243.205 0)
			(effects
				(font
					(size 1.27 1.27)
				)
			)
		)
		(property "MPN" ""
			(at 387.985 243.205 0)
			(effects
				(font
					(size 1.27 1.27)
				)
				(hide yes)
			)
		)
		(property "Manufacturer" ""
			(at 403.225 263.525 0)
			(effects
				(font
					(size 1.27 1.27)
					(thickness 0.15)
				)
				(justify left bottom)
				(hide yes)
			)
		)
		(property "Author" "Antmicro"
			(at 403.225 258.445 0)
			(effects
				(font
					(size 1.27 1.27)
					(thickness 0.15)
				)
				(justify left bottom)
				(hide yes)
			)
		)
		(property "License" "Apache-2.0"
			(at 403.225 260.985 0)
			(effects
				(font
					(size 1.27 1.27)
					(thickness 0.15)
				)
				(justify left bottom)
				(hide yes)
			)
		)
		(instances
			(project "ddr5-testbed"
				(path ""
					(reference "N1")
					(unit 1)
				)
			)
		)
	)
	(sheet
		(at 194.31 140.97)
		(size 41.91 28.575)
		(exclude_from_sim no)
		(in_bom yes)
		(on_board yes)
		(dnp no)
		(fields_autoplaced yes)
		(stroke
			(width 0)
			(type solid)
		)
		(fill
			(color 0 0 0 0.0000)
		)
		(property "Sheetname" "SODIMM"
			(at 194.31 140.2584 0)
			(effects
				(font
					(size 1.27 1.27)
				)
				(justify left bottom)
			)
		)
		(property "Sheetfile" "sodim.kicad_sch"
			(at 194.31 170.1296 0)
			(effects
				(font
					(size 1.27 1.27)
				)
				(justify left top)
			)
		)
		(instances
			(project "ddr5-testbed"
				(path ""
					(page "3")
				)
			)
		)
	)
	(sheet
		(at 254 140.335)
		(size 41.91 28.575)
		(exclude_from_sim no)
		(in_bom yes)
		(on_board yes)
		(dnp no)
		(fields_autoplaced yes)
		(stroke
			(width 0)
			(type solid)
		)
		(fill
			(color 0 0 0 0.0000)
		)
		(property "Sheetname" "DDR5"
			(at 254 139.6234 0)
			(effects
				(font
					(size 1.27 1.27)
				)
				(justify left bottom)
			)
		)
		(property "Sheetfile" "ddr5.kicad_sch"
			(at 254 169.4946 0)
			(effects
				(font
					(size 1.27 1.27)
				)
				(justify left top)
			)
		)
		(instances
			(project "ddr5-testbed"
				(path ""
					(page "4")
				)
			)
		)
	)
	(sheet
		(at 136.525 141.605)
		(size 40.64 27.94)
		(exclude_from_sim no)
		(in_bom yes)
		(on_board yes)
		(dnp no)
		(fields_autoplaced yes)
		(stroke
			(width 0)
			(type solid)
		)
		(fill
			(color 0 0 0 0.0000)
		)
		(property "Sheetname" "EEPROM"
			(at 136.525 140.8934 0)
			(effects
				(font
					(size 1.27 1.27)
				)
				(justify left bottom)
			)
		)
		(property "Sheetfile" "EEPROM.kicad_sch"
			(at 136.525 170.1296 0)
			(effects
				(font
					(size 1.27 1.27)
				)
				(justify left top)
			)
		)
		(instances
			(project "ddr5-testbed"
				(path ""
					(page "2")
				)
			)
		)
	)
	(sheet_instances
		(path "/"
			(page "1")
		)
	)
)
